# T6G (Grand Teton) — schematic netlist excerpt (pin names and nets, part order shuffled) for the footprints in the layout excerpt that follows; sources: Cadence DE-HDL packaged netlist, KiCad conversion of 04192023_DAF0TMB3IC0_F0TG_MB_C_brd_V02_OCP.brd

PU19  ISL99390FRZTR5935  ISL99390FRZ-TR5935 IC  pkg QFN21_6X5XB  page 206
  VOS  = PVDDIO_P0_VOS3
  AGND  = GND
  VCC  = PVDDIO_P0_VCC3
  PVCC  = PVDDCR_CPU1_P0_PVCC
  PGND1  = GND
  GL1  = NC_PVDDIO_P0_GL1_3
  PGND2  = GND
  SW  = SW_PVDDIO_P0_SW3
  VIN1  = SW_P12V_AUX_PVDDIO_P0_FLT
  VIN2  = SW_P12V_AUX_PVDDIO_P0_FLT
  DNC  = NC_PVDDIO_P0_DNC3
  PHASE  = SW_PVDDIO_P0_BOOTR3
  BOOT  = SW_PVDDIO_P0_BOOT3
  PWM  = PVDDIO_P0_PWM3
  EN  = PVDDIO_P0_VCC3
  TOUT_FLT  = PVDDIO_P0_TEMP1
  LSET  = PVDDIO_P0_LSET3
  IOUT  = PVDDIO_P0_IMON3
  REFIN  = PVDDCR_CPU1_P0_VCCS
  PGND3  = GND
  GL2  = NC_PVDDIO_P0_GL2_3

(kicad_pcb
	(version 20260206)
	(generator "pcbnew")
	(generator_version "10.0")
	(general
		(thickness 1.6)
		(legacy_teardrops no)
	)
	(paper "A4")
	(title_block
		(title "04192023_DAF0TMB3IC0_F0TG_MB_C_brd_V02_OCP.brd")
		(comment 1 "Grand Teton / footprints 1265-1265 of 8354")
	)
	(layers
		(0 "F.Cu" signal "TOP")
		(4 "In1.Cu" signal "GND")
		(6 "In2.Cu" signal "IN1")
		(8 "In3.Cu" signal "GND1")
		(10 "In4.Cu" signal "IN2")
		(12 "In5.Cu" signal "GND2")
		(14 "In6.Cu" signal "IN3")
		(16 "In7.Cu" signal "GND3")
		(18 "In8.Cu" signal "VCC")
		(20 "In9.Cu" signal "VCC1")
		(22 "In10.Cu" signal "GND4")
		(24 "In11.Cu" signal "IN4")
		(26 "In12.Cu" signal "GND5")
		(28 "In13.Cu" signal "IN5")
		(30 "In14.Cu" signal "GND6")
		(32 "In15.Cu" signal "IN6")
		(34 "In16.Cu" signal "GND7")
		(2 "B.Cu" signal "BOTTOM")
		(9 "F.Adhes" user "F.Adhesive")
		(11 "B.Adhes" user "B.Adhesive")
		(13 "F.Paste" user "Package Geometry/Pastemask Top")
		(15 "B.Paste" user "Package Geometry/Pastemask Bottom")
		(5 "F.SilkS" user "Ref Des/Silkscreen Top")
		(7 "B.SilkS" user "Ref Des/Silkscreen Bottom")
		(1 "F.Mask" user "Board Geometry/Soldermask Top")
		(3 "B.Mask" user "Board Geometry/Soldermask Bottom")
		(17 "Dwgs.User" user "User.Drawings")
		(19 "Cmts.User" user "User.Comments")
		(21 "Eco1.User" user "User.Eco1")
		(23 "Eco2.User" user "User.Eco2")
		(25 "Edge.Cuts" user "Board Geometry/Outline")
		(27 "Margin" user)
		(31 "F.CrtYd" user "Package Geometry/Place Bound Top")
		(29 "B.CrtYd" user "Package Geometry/Place Bound Bottom")
		(35 "F.Fab" user "Ref Des/Assembly Top")
		(33 "B.Fab" user "Ref Des/Assembly Bottom")
	)
	(footprint ""
		(layer "F.Cu")
		(at 283.702506 -346.71635)
		(property "Reference" "PU19"
			(at -2.524506 -7.84098 0)
			(unlocked yes)
			(layer "F.SilkS")
			(effects
				(font
					(size 0.7874 0.5842)
					(thickness 0.1524)
				)
				(justify left)
			)
		)
		(property "Value" ""
			(at 0 0 0)
			(layer "F.Fab")
			(effects
				(font
					(size 1.27 1.27)
				)
			)
		)
		(duplicate_pad_numbers_are_jumpers no)
		(fp_line
			(start -2.500122 -2.999994)
			(end -2.24409 -2.999994)
			(stroke
				(width 0.1524)
				(type default)
			)
			(layer "F.SilkS")
		)
		(fp_line
			(start -2.500122 -2.529078)
			(end -2.500122 -2.999994)
			(stroke
				(width 0.1524)
				(type default)
			)
			(layer "F.SilkS")
		)
		(fp_line
			(start -2.500122 0.6604)
			(end -2.500122 0.229108)
			(stroke
				(width 0.1524)
				(type default)
			)
			(layer "F.SilkS")
		)
		(fp_line
			(start -2.500122 2.999994)
			(end -2.500122 2.339594)
			(stroke
				(width 0.1524)
				(type default)
			)
			(layer "F.SilkS")
		)
		(fp_line
			(start -2.2987 2.999994)
			(end -2.500122 2.999994)
			(stroke
				(width 0.1524)
				(type default)
			)
			(layer "F.SilkS")
		)
		(fp_line
			(start 2.31394 -2.999994)
			(end 2.500122 -2.999994)
			(stroke
				(width 0.1524)
				(type default)
			)
			(layer "F.SilkS")
		)
		(fp_line
			(start 2.500122 -2.999994)
			(end 2.500122 -2.44348)
			(stroke
				(width 0.1524)
				(type default)
			)
			(layer "F.SilkS")
		)
		(fp_line
			(start 2.500122 2.339594)
			(end 2.500122 2.999994)
			(stroke
				(width 0.1524)
				(type default)
			)
			(layer "F.SilkS")
		)
		(fp_line
			(start 2.500122 2.999994)
			(end 2.2987 2.999994)
			(stroke
				(width 0.1524)
				(type default)
			)
			(layer "F.SilkS")
		)
		(fp_poly
			(pts
				(xy -3.467354 -2.685288) (xy -2.981706 -3.170936) (xy -2.738882 -2.442464)
			)
			(stroke
				(width 0)
				(type default)
			)
			(fill yes)
			(layer "F.SilkS")
		)
		(fp_line
			(start -2.500122 -2.999994)
			(end 2.500122 -2.999994)
			(stroke
				(width 0.1)
				(type default)
			)
			(layer "F.Fab")
		)
		(fp_line
			(start -2.500122 2.999994)
			(end -2.500122 -2.999994)
			(stroke
				(width 0.1)
				(type default)
			)
			(layer "F.Fab")
		)
		(fp_line
			(start 2.500122 -2.999994)
			(end 2.500122 2.999994)
			(stroke
				(width 0.1)
				(type default)
			)
			(layer "F.Fab")
		)
		(fp_line
			(start 2.500122 2.999994)
			(end -2.500122 2.999994)
			(stroke
				(width 0.1)
				(type default)
			)
			(layer "F.Fab")
		)
		(fp_poly
			(pts
				(xy -4.218432 -2.783078) (xy -4.218432 -1.767078) (xy -3.202432 -2.275078)
			)
			(stroke
				(width 0)
				(type default)
			)
			(fill yes)
			(layer "F.Fab")
		)
		(pad "1" smd rect
			(at -2.400046 -2.275078 90)
			(size 0.2286 0.6096)
			(layers "F.Cu" "F.Mask" "F.Paste")
			(net "PVDDIO_P0_VOS3")
		)
		(pad "2" smd rect
			(at -2.400046 -1.82499 90)
			(size 0.2286 0.6096)
			(layers "F.Cu" "F.Mask" "F.Paste")
			(net "GND")
		)
		(pad "3" smd rect
			(at -2.400046 -1.374902 90)
			(size 0.2286 0.6096)
			(layers "F.Cu" "F.Mask" "F.Paste")
			(net "PVDDIO_P0_VCC3")
		)
		(pad "4" smd rect
			(at -2.400046 -0.925068 90)
			(size 0.2286 0.6096)
			(layers "F.Cu" "F.Mask" "F.Paste")
			(net "PVDDCR_CPU1_P0_PVCC")
		)
		(pad "5" smd rect
			(at -2.400046 -0.47498 90)
			(size 0.2286 0.6096)
			(layers "F.Cu" "F.Mask" "F.Paste")
			(net "GND")
		)
		(pad "6" smd rect
			(at -2.400046 -0.024892 90)
			(size 0.2286 0.6096)
			(layers "F.Cu" "F.Mask" "F.Paste")
			(net "NC_PVDDIO_P0_GL1_3")
		)
		(pad "7_9-20_24" smd circle
			(at 0 1.150112 90)
			(size 0 0)
			(layers "F.Cu" "F.Mask" "F.Paste")
			(net "GND")
		)
		(pad "10_19" smd rect
			(at 0 2.899918 90)
			(size 0.6096 4.318)
			(layers "F.Cu" "F.Mask" "F.Paste")
			(net "SW_PVDDIO_P0_SW3")
		)
		(pad "25_29" smd rect
			(at 1.549908 -1.279906 270)
			(size 2.0574 2.3114)
			(layers "F.Cu" "F.Mask" "F.Paste")
			(net "SW_P12V_AUX_PVDDIO_P0_FLT")
		)
		(pad "30" smd rect
			(at 2.05994 -2.899918)
			(size 0.2286 0.6096)
			(layers "F.Cu" "F.Mask" "F.Paste")
			(net "SW_P12V_AUX_PVDDIO_P0_FLT")
		)
		(pad "31" smd rect
			(at 1.610106 -2.899918)
			(size 0.2286 0.6096)
			(layers "F.Cu" "F.Mask" "F.Paste")
			(net "NC_PVDDIO_P0_DNC3")
		)
		(pad "32" smd rect
			(at 1.160018 -2.899918)
			(size 0.2286 0.6096)
			(layers "F.Cu" "F.Mask" "F.Paste")
			(net "SW_PVDDIO_P0_BOOTR3")
		)
		(pad "33" smd rect
			(at 0.70993 -2.899918)
			(size 0.2286 0.6096)
			(layers "F.Cu" "F.Mask" "F.Paste")
			(net "SW_PVDDIO_P0_BOOT3")
		)
		(pad "34" smd rect
			(at 0.260096 -2.899918)
			(size 0.2286 0.6096)
			(layers "F.Cu" "F.Mask" "F.Paste")
			(net "PVDDIO_P0_PWM3")
		)
		(pad "35" smd rect
			(at -0.189992 -2.899918)
			(size 0.2286 0.6096)
			(layers "F.Cu" "F.Mask" "F.Paste")
			(net "PVDDIO_P0_VCC3")
		)
		(pad "36" smd rect
			(at -0.64008 -2.899918)
			(size 0.2286 0.6096)
			(layers "F.Cu" "F.Mask" "F.Paste")
			(net "PVDDIO_P0_TEMP1")
		)
		(pad "37" smd rect
			(at -1.089914 -2.899918)
			(size 0.2286 0.6096)
			(layers "F.Cu" "F.Mask" "F.Paste")
			(net "PVDDIO_P0_LSET3")
		)
		(pad "38" smd rect
			(at -1.540002 -2.899918)
			(size 0.2286 0.6096)
			(layers "F.Cu" "F.Mask" "F.Paste")
			(net "PVDDIO_P0_IMON3")
		)
		(pad "39" smd rect
			(at -1.99009 -2.899918)
			(size 0.2286 0.6096)
			(layers "F.Cu" "F.Mask" "F.Paste")
			(net "PVDDCR_CPU1_P0_VCCS")
		)
		(pad "40" smd rect
			(at -0.87503 -1.27508)
			(size 1.7526 1.9558)
			(layers "F.Cu" "F.Mask" "F.Paste")
			(net "GND")
		)
		(pad "41" smd rect
			(at -1.525016 0.249936 270)
			(size 0.3048 0.4572)
			(layers "F.Cu" "F.Mask" "F.Paste")
			(net "NC_PVDDIO_P0_GL2_3")
		)
		(zone
			(layer "F.Cu")
			(hatch none 0.5)
			(connect_pads
				(clearance 0)
			)
			(min_thickness 0.25)
			(keepout
				(tracks not_allowed)
				(vias allowed)
				(pads allowed)
				(copperpour not_allowed)
				(footprints allowed)
			)
			(placement
				(enabled no)
				(sheetname "")
			)
			(fill
				(thermal_gap 0.5)
				(thermal_bridge_width 0.5)
				(island_removal_mode 0)
			)
			(polygon
				(pts
					(xy 281.202384 -344.124788) (xy 281.202384 -344.465656) (xy 286.202628 -344.465656) (xy 286.202628 -344.13063)
					(xy 285.912306 -344.13063) (xy 285.912306 -344.172032) (xy 281.492706 -344.172032) (xy 281.492706 -344.124788)
				)
			)
		)
		(zone
			(layer "F.Cu")
			(hatch none 0.5)
			(connect_pads
				(clearance 0)
			)
			(min_thickness 0.25)
			(keepout
				(tracks not_allowed)
				(vias allowed)
				(pads allowed)
				(copperpour not_allowed)
				(footprints allowed)
			)
			(placement
				(enabled no)
				(sheetname "")
			)
			(fill
				(thermal_gap 0.5)
				(thermal_bridge_width 0.5)
				(island_removal_mode 0)
			)
			(polygon
				(pts
					(xy 283.754576 -346.96273) (xy 283.754576 -349.02013) (xy 281.900376 -349.02013) (xy 281.900376 -348.779084)
					(xy 281.65806 -348.779084) (xy 281.65806 -349.260668) (xy 285.474918 -349.260668) (xy 285.474918 -349.075756)
					(xy 284.045914 -349.075756) (xy 284.045914 -346.916756) (xy 286.202628 -346.916756) (xy 286.202628 -346.667074)
					(xy 284.050232 -346.667074)
				)
			)
		)
	)
)
